(kicad_pcb
	(version 20260206)
	(generator "pcbnew")
	(generator_version "10.0")
	(general
		(thickness 1.6)
		(legacy_teardrops no)
	)
	(paper "A4")
	(title_block
		(title "Bryce Canyon_IOM_IOC_16318-2_OCP.brd")
		(comment 1 "Bryce Canyon / footprints 1329-1332 of 1605")
	)
	(layers
		(0 "F.Cu" signal "TOP")
		(4 "In1.Cu" signal "L2GND")
		(6 "In2.Cu" signal "L3")
		(8 "In3.Cu" signal "L4VCC")
		(10 "In4.Cu" signal "L5VCC")
		(12 "In5.Cu" signal "L6")
		(14 "In6.Cu" signal "L7GND")
		(2 "B.Cu" signal "BOTTOM")
		(9 "F.Adhes" user "F.Adhesive")
		(11 "B.Adhes" user "B.Adhesive")
		(13 "F.Paste" user "Package Geometry/Pastemask Top")
		(15 "B.Paste" user "Package Geometry/Pastemask Bottom")
		(5 "F.SilkS" user "Ref Des/Silkscreen Top")
		(7 "B.SilkS" user "Ref Des/Silkscreen Bottom")
		(1 "F.Mask" user "Board Geometry/Soldermask Top")
		(3 "B.Mask" user "Board Geometry/Soldermask Bottom")
		(17 "Dwgs.User" user "User.Drawings")
		(19 "Cmts.User" user "User.Comments")
		(21 "Eco1.User" user "User.Eco1")
		(23 "Eco2.User" user "User.Eco2")
		(25 "Edge.Cuts" user "Board Geometry/Outline")
		(27 "Margin" user)
		(31 "F.CrtYd" user "Package Geometry/Place Bound Top")
		(29 "B.CrtYd" user "Package Geometry/Place Bound Bottom")
		(35 "F.Fab" user "Ref Des/Assembly Top")
		(33 "B.Fab" user "Ref Des/Assembly Bottom")
	)
	(footprint ""
		(layer "B.Cu")
		(at 38.231064 -144.857216 -90)
		(property "Reference" "C71"
			(at 0 0 90)
			(layer "B.SilkS")
			(hide yes)
			(effects
				(font
					(size 1.27 1.27)
				)
				(justify mirror)
			)
		)
		(property "Value" "SCD1U16V2KX-3GP"
			(at -1.1811 -2.7051 270)
			(unlocked yes)
			(layer "B.Fab")
			(hide yes)
			(effects
				(font
					(size 1.016 1.016)
					(thickness 0.1524)
				)
				(justify mirror)
			)
		)
		(property "Device Type" "C402H22"
			(at -1.1811 -4.2291 270)
			(unlocked yes)
			(layer "B.Fab")
			(hide yes)
			(effects
				(font
					(size 1.016 1.016)
					(thickness 0.1524)
				)
				(justify mirror)
			)
		)
		(duplicate_pad_numbers_are_jumpers no)
		(fp_rect
			(start 0.4318 0.9525)
			(end -0.4318 -0.9525)
			(stroke
				(width 0)
				(type default)
			)
			(fill no)
			(layer "B.CrtYd")
		)
		(fp_rect
			(start 0.4318 0.9525)
			(end -0.4318 -0.9525)
			(stroke
				(width 0)
				(type default)
			)
			(fill no)
			(layer "B.Fab")
		)
		(pad "1" smd custom
			(at 0 -0.4445 90)
			(size 0.1524 0.1524)
			(layers "B.Cu" "B.Mask" "B.Paste")
			(net "GND")
			(options
				(clearance outline)
				(anchor circle)
			)
			(primitives
				(gr_poly
					(pts
						(arc
							(start 0.3048 0.2032)
							(mid 0.275042 0.275042)
							(end 0.2032 0.3048)
						)
						(arc
							(start -0.2032 0.3048)
							(mid -0.275042 0.275042)
							(end -0.3048 0.2032)
						)
						(arc
							(start -0.3048 -0.2032)
							(mid -0.275042 -0.275042)
							(end -0.2032 -0.3048)
						)
						(arc
							(start 0.2032 -0.3048)
							(mid 0.275042 -0.275042)
							(end 0.3048 -0.2032)
						)
					)
					(width 0)
					(fill yes)
				)
			)
		)
		(pad "2" smd custom
			(at 0 0.4445 90)
			(size 0.1524 0.1524)
			(layers "B.Cu" "B.Mask" "B.Paste")
			(net "P1V2_STBY")
			(options
				(clearance outline)
				(anchor circle)
			)
			(primitives
				(gr_poly
					(pts
						(arc
							(start 0.3048 0.2032)
							(mid 0.275042 0.275042)
							(end 0.2032 0.3048)
						)
						(arc
							(start -0.2032 0.3048)
							(mid -0.275042 0.275042)
							(end -0.3048 0.2032)
						)
						(arc
							(start -0.3048 -0.2032)
							(mid -0.275042 -0.275042)
							(end -0.2032 -0.3048)
						)
						(arc
							(start 0.2032 -0.3048)
							(mid 0.275042 -0.275042)
							(end 0.3048 -0.2032)
						)
					)
					(width 0)
					(fill yes)
				)
			)
		)
	)
	(footprint ""
		(layer "B.Cu")
		(at 93.6752 -170.6626 90)
		(property "Reference" "R795"
			(at 0 0 90)
			(layer "B.SilkS")
			(hide yes)
			(effects
				(font
					(size 1.27 1.27)
				)
				(justify mirror)
			)
		)
		(property "Value" "0R2J-2-GP"
			(at -0.064008 -3.993896 90)
			(unlocked yes)
			(layer "B.Fab")
			(hide yes)
			(effects
				(font
					(size 1.016 1.016)
					(thickness 0.1524)
				)
				(justify mirror)
			)
		)
		(property "Device Type" "R402H16"
			(at -0.064008 -5.517896 90)
			(unlocked yes)
			(layer "B.Fab")
			(hide yes)
			(effects
				(font
					(size 1.016 1.016)
					(thickness 0.1524)
				)
				(justify mirror)
			)
		)
		(duplicate_pad_numbers_are_jumpers no)
		(fp_line
			(start 0.508 -0.9398)
			(end 0.508 0.9398)
			(stroke
				(width 0.1524)
				(type default)
			)
			(layer "B.SilkS")
		)
		(fp_line
			(start -0.508 -0.9398)
			(end 0.508 -0.9398)
			(stroke
				(width 0.1524)
				(type default)
			)
			(layer "B.SilkS")
		)
		(fp_rect
			(start 0.508 0.9398)
			(end -0.508 -0.9398)
			(stroke
				(width 0)
				(type default)
			)
			(fill no)
			(layer "B.CrtYd")
		)
		(fp_rect
			(start 0.508 0.9398)
			(end -0.508 -0.9398)
			(stroke
				(width 0)
				(type default)
			)
			(fill no)
			(layer "B.Fab")
		)
		(pad "1" smd custom
			(at 0 -0.4445 270)
			(size 0.1397 0.1397)
			(layers "B.Cu" "B.Mask" "B.Paste")
			(net "UART_COMP_IN_RX_AND_R")
			(options
				(clearance outline)
				(anchor circle)
			)
			(primitives
				(gr_poly
					(pts
						(arc
							(start -0.1778 0.2794)
							(mid -0.249642 0.249642)
							(end -0.2794 0.1778)
						)
						(arc
							(start -0.2794 -0.1778)
							(mid -0.249642 -0.249642)
							(end -0.1778 -0.2794)
						)
						(arc
							(start 0.1778 -0.2794)
							(mid 0.249642 -0.249642)
							(end 0.2794 -0.1778)
						)
						(arc
							(start 0.2794 0.1778)
							(mid 0.249642 0.249642)
							(end 0.1778 0.2794)
						)
					)
					(width 0)
					(fill yes)
				)
			)
		)
		(pad "2" smd custom
			(at 0 0.4445 270)
			(size 0.1397 0.1397)
			(layers "B.Cu" "B.Mask" "B.Paste")
			(net "UART_COMP_IN_RX_AND")
			(options
				(clearance outline)
				(anchor circle)
			)
			(primitives
				(gr_poly
					(pts
						(arc
							(start -0.1778 0.2794)
							(mid -0.249642 0.249642)
							(end -0.2794 0.1778)
						)
						(arc
							(start -0.2794 -0.1778)
							(mid -0.249642 -0.249642)
							(end -0.1778 -0.2794)
						)
						(arc
							(start 0.1778 -0.2794)
							(mid 0.249642 -0.249642)
							(end 0.2794 -0.1778)
						)
						(arc
							(start 0.2794 0.1778)
							(mid 0.249642 0.249642)
							(end 0.1778 0.2794)
						)
					)
					(width 0)
					(fill yes)
				)
			)
		)
	)
	(footprint ""
		(layer "B.Cu")
		(at 180.512466 -65.522856 90)
		(property "Reference" "R575"
			(at 0 0 90)
			(layer "B.SilkS")
			(hide yes)
			(effects
				(font
					(size 1.27 1.27)
				)
				(justify mirror)
			)
		)
		(property "Value" "10KR2F-2-GP"
			(at -0.064008 -3.993896 90)
			(unlocked yes)
			(layer "B.Fab")
			(hide yes)
			(effects
				(font
					(size 1.016 1.016)
					(thickness 0.1524)
				)
				(justify mirror)
			)
		)
		(property "Device Type" "R402H16"
			(at -0.064008 -5.517896 90)
			(unlocked yes)
			(layer "B.Fab")
			(hide yes)
			(effects
				(font
					(size 1.016 1.016)
					(thickness 0.1524)
				)
				(justify mirror)
			)
		)
		(duplicate_pad_numbers_are_jumpers no)
		(fp_line
			(start 0.508 -0.9398)
			(end 0.508 0.9398)
			(stroke
				(width 0.1524)
				(type default)
			)
			(layer "B.SilkS")
		)
		(fp_line
			(start -0.508 -0.9398)
			(end 0.508 -0.9398)
			(stroke
				(width 0.1524)
				(type default)
			)
			(layer "B.SilkS")
		)
		(fp_rect
			(start 0.508 0.9398)
			(end -0.508 -0.9398)
			(stroke
				(width 0)
				(type default)
			)
			(fill no)
			(layer "B.CrtYd")
		)
		(fp_rect
			(start 0.508 0.9398)
			(end -0.508 -0.9398)
			(stroke
				(width 0)
				(type default)
			)
			(fill no)
			(layer "B.Fab")
		)
		(pad "1" smd custom
			(at 0 -0.4445 270)
			(size 0.1397 0.1397)
			(layers "B.Cu" "B.Mask" "B.Paste")
			(net "GND")
			(options
				(clearance outline)
				(anchor circle)
			)
			(primitives
				(gr_poly
					(pts
						(arc
							(start -0.1778 0.2794)
							(mid -0.249642 0.249642)
							(end -0.2794 0.1778)
						)
						(arc
							(start -0.2794 -0.1778)
							(mid -0.249642 -0.249642)
							(end -0.1778 -0.2794)
						)
						(arc
							(start 0.1778 -0.2794)
							(mid 0.249642 -0.249642)
							(end 0.2794 -0.1778)
						)
						(arc
							(start 0.2794 0.1778)
							(mid 0.249642 0.249642)
							(end 0.1778 0.2794)
						)
					)
					(width 0)
					(fill yes)
				)
			)
		)
		(pad "2" smd custom
			(at 0 0.4445 270)
			(size 0.1397 0.1397)
			(layers "B.Cu" "B.Mask" "B.Paste")
			(net "IOC_CLK_SEL1")
			(options
				(clearance outline)
				(anchor circle)
			)
			(primitives
				(gr_poly
					(pts
						(arc
							(start -0.1778 0.2794)
							(mid -0.249642 0.249642)
							(end -0.2794 0.1778)
						)
						(arc
							(start -0.2794 -0.1778)
							(mid -0.249642 -0.249642)
							(end -0.1778 -0.2794)
						)
						(arc
							(start 0.1778 -0.2794)
							(mid 0.249642 -0.249642)
							(end 0.2794 -0.1778)
						)
						(arc
							(start 0.2794 0.1778)
							(mid 0.249642 0.249642)
							(end 0.1778 0.2794)
						)
					)
					(width 0)
					(fill yes)
				)
			)
		)
	)
	(footprint ""
		(layer "B.Cu")
		(at 164.7444 -63.2714 180)
		(property "Reference" "U42"
			(at 0 0 0)
			(layer "B.SilkS")
			(hide yes)
			(effects
				(font
					(size 1.27 1.27)
				)
				(justify mirror)
			)
		)
		(property "Value" "S29GL128S10TFIV20-GP"
			(at 0.1778 -20.32 180)
			(unlocked yes)
			(layer "B.Fab")
			(hide yes)
			(effects
				(font
					(size 1.016 1.016)
					(thickness 0.1524)
				)
				(justify mirror)
			)
		)
		(property "Device Type" "TSOP56-1H48"
			(at 0.1778 -22.225 180)
			(unlocked yes)
			(layer "B.Fab")
			(hide yes)
			(effects
				(font
					(size 1.016 1.016)
					(thickness 0.1524)
				)
				(justify mirror)
			)
		)
		(duplicate_pad_numbers_are_jumpers no)
		(fp_line
			(start 7.5438 8.5598)
			(end -6.8326 8.5598)
			(stroke
				(width 0.1524)
				(type default)
			)
			(layer "B.SilkS")
		)
		(fp_line
			(start 7.5438 -0.4318)
			(end 7.112 0)
			(stroke
				(width 0.1524)
				(type default)
			)
			(layer "B.SilkS")
		)
		(fp_line
			(start 7.5438 -8.5598)
			(end 7.5438 8.5598)
			(stroke
				(width 0.1524)
				(type default)
			)
			(layer "B.SilkS")
		)
		(fp_line
			(start 7.366 8.5598)
			(end 7.366 10.795)
			(stroke
				(width 0.508)
				(type default)
			)
			(layer "B.SilkS")
		)
		(fp_line
			(start 7.112 0)
			(end 7.5438 0.4318)
			(stroke
				(width 0.1524)
				(type default)
			)
			(layer "B.SilkS")
		)
		(fp_line
			(start -6.8326 8.5598)
			(end -6.8326 -8.5598)
			(stroke
				(width 0.1524)
				(type default)
			)
			(layer "B.SilkS")
		)
		(fp_line
			(start -6.8326 -8.5598)
			(end 7.5438 -8.5598)
			(stroke
				(width 0.1524)
				(type default)
			)
			(layer "B.SilkS")
		)
		(fp_poly
			(pts
				(xy 7.62 11.049) (xy -7.62 11.049) (xy -7.62 -11.049) (xy 7.62 -11.049)
			)
			(stroke
				(width 0)
				(type default)
			)
			(fill no)
			(layer "B.CrtYd")
		)
		(fp_poly
			(pts
				(xy 7.62 -11.049) (xy -7.62 -11.049) (xy -7.62 11.049) (xy 7.62 11.049)
			)
			(stroke
				(width 0)
				(type default)
			)
			(fill no)
			(layer "B.Fab")
		)
		(pad "1" smd rect
			(at 6.75005 9.6139)
			(size 0.3048 1.524)
			(layers "B.Cu" "B.Mask" "B.Paste")
			(net "Net_319")
		)
		(pad "2" smd rect
			(at 6.24967 9.6139)
			(size 0.3048 1.524)
			(layers "B.Cu" "B.Mask" "B.Paste")
			(net "XM_ADDR_23")
		)
		(pad "3" smd rect
			(at 5.75056 9.6139)
			(size 0.3048 1.524)
			(layers "B.Cu" "B.Mask" "B.Paste")
			(net "XM_ADDR_16")
		)
		(pad "4" smd rect
			(at 5.25018 9.6139)
			(size 0.3048 1.524)
			(layers "B.Cu" "B.Mask" "B.Paste")
			(net "XM_ADDR_15")
		)
		(pad "5" smd rect
			(at 4.7498 9.6139)
			(size 0.3048 1.524)
			(layers "B.Cu" "B.Mask" "B.Paste")
			(net "XM_ADDR_14")
		)
		(pad "6" smd rect
			(at 4.24942 9.6139)
			(size 0.3048 1.524)
			(layers "B.Cu" "B.Mask" "B.Paste")
			(net "XM_ADDR_13")
		)
		(pad "7" smd rect
			(at 3.75031 9.6139)
			(size 0.3048 1.524)
			(layers "B.Cu" "B.Mask" "B.Paste")
			(net "XM_ADDR_12")
		)
		(pad "8" smd rect
			(at 3.24993 9.6139)
			(size 0.3048 1.524)
			(layers "B.Cu" "B.Mask" "B.Paste")
			(net "XM_ADDR_11")
		)
		(pad "9" smd rect
			(at 2.74955 9.6139)
			(size 0.3048 1.524)
			(layers "B.Cu" "B.Mask" "B.Paste")
			(net "XM_ADDR_10")
		)
		(pad "10" smd rect
			(at 2.25044 9.6139)
			(size 0.3048 1.524)
			(layers "B.Cu" "B.Mask" "B.Paste")
			(net "XM_ADDR_9")
		)
		(pad "11" smd rect
			(at 1.75006 9.6139)
			(size 0.3048 1.524)
			(layers "B.Cu" "B.Mask" "B.Paste")
			(net "XM_ADDR_20")
		)
		(pad "12" smd rect
			(at 1.24968 9.6139)
			(size 0.3048 1.524)
			(layers "B.Cu" "B.Mask" "B.Paste")
			(net "XM_ADDR_21")
		)
		(pad "13" smd rect
			(at 0.75057 9.6139)
			(size 0.3048 1.524)
			(layers "B.Cu" "B.Mask" "B.Paste")
			(net "XM_WE_N")
		)
		(pad "14" smd rect
			(at 0.25019 9.6139)
			(size 0.3048 1.524)
			(layers "B.Cu" "B.Mask" "B.Paste")
			(net "XM_F_RST_N")
		)
		(pad "15" smd rect
			(at -0.25019 9.6139)
			(size 0.3048 1.524)
			(layers "B.Cu" "B.Mask" "B.Paste")
			(net "XM_ADDR_22")
		)
		(pad "16" smd rect
			(at -0.75057 9.6139)
			(size 0.3048 1.524)
			(layers "B.Cu" "B.Mask" "B.Paste")
			(net "IOC_WP_N")
		)
		(pad "17" smd rect
			(at -1.24968 9.6139)
			(size 0.3048 1.524)
			(layers "B.Cu" "B.Mask" "B.Paste")
			(net "Net_314")
		)
		(pad "18" smd rect
			(at -1.75006 9.6139)
			(size 0.3048 1.524)
			(layers "B.Cu" "B.Mask" "B.Paste")
			(net "XM_ADDR_19")
		)
		(pad "19" smd rect
			(at -2.25044 9.6139)
			(size 0.3048 1.524)
			(layers "B.Cu" "B.Mask" "B.Paste")
			(net "XM_ADDR_18")
		)
		(pad "20" smd rect
			(at -2.74955 9.6139)
			(size 0.3048 1.524)
			(layers "B.Cu" "B.Mask" "B.Paste")
			(net "XM_ADDR_8")
		)
		(pad "21" smd rect
			(at -3.24993 9.6139)
			(size 0.3048 1.524)
			(layers "B.Cu" "B.Mask" "B.Paste")
			(net "XM_ADDR_7")
		)
		(pad "22" smd rect
			(at -3.75031 9.6139)
			(size 0.3048 1.524)
			(layers "B.Cu" "B.Mask" "B.Paste")
			(net "XM_ADDR_6")
		)
		(pad "23" smd rect
			(at -4.24942 9.6139)
			(size 0.3048 1.524)
			(layers "B.Cu" "B.Mask" "B.Paste")
			(net "XM_ADDR_5")
		)
		(pad "24" smd rect
			(at -4.7498 9.6139)
			(size 0.3048 1.524)
			(layers "B.Cu" "B.Mask" "B.Paste")
			(net "XM_ADDR_4")
		)
		(pad "25" smd rect
			(at -5.25018 9.6139)
			(size 0.3048 1.524)
			(layers "B.Cu" "B.Mask" "B.Paste")
			(net "XM_ADDR_3")
		)
		(pad "26" smd rect
			(at -5.75056 9.6139)
			(size 0.3048 1.524)
			(layers "B.Cu" "B.Mask" "B.Paste")
			(net "XM_ADDR_2")
		)
		(pad "27" smd rect
			(at -6.24967 9.6139)
			(size 0.3048 1.524)
			(layers "B.Cu" "B.Mask" "B.Paste")
			(net "Net_315")
		)
		(pad "28" smd rect
			(at -6.75005 9.6139)
			(size 0.3048 1.524)
			(layers "B.Cu" "B.Mask" "B.Paste")
			(net "Net_316")
		)
		(pad "29" smd rect
			(at -6.75005 -9.6139)
			(size 0.3048 1.524)
			(layers "B.Cu" "B.Mask" "B.Paste")
			(net "P1V8")
		)
		(pad "30" smd rect
			(at -6.24967 -9.6139)
			(size 0.3048 1.524)
			(layers "B.Cu" "B.Mask" "B.Paste")
			(net "Net_313")
		)
		(pad "31" smd rect
			(at -5.75056 -9.6139)
			(size 0.3048 1.524)
			(layers "B.Cu" "B.Mask" "B.Paste")
			(net "XM_ADDR_1")
		)
		(pad "32" smd rect
			(at -5.25018 -9.6139)
			(size 0.3048 1.524)
			(layers "B.Cu" "B.Mask" "B.Paste")
			(net "XM_NOR_CS_N")
		)
		(pad "33" smd rect
			(at -4.7498 -9.6139)
			(size 0.3048 1.524)
			(layers "B.Cu" "B.Mask" "B.Paste")
			(net "GND")
		)
		(pad "34" smd rect
			(at -4.24942 -9.6139)
			(size 0.3048 1.524)
			(layers "B.Cu" "B.Mask" "B.Paste")
			(net "XM_OE_N")
		)
		(pad "35" smd rect
			(at -3.75031 -9.6139)
			(size 0.3048 1.524)
			(layers "B.Cu" "B.Mask" "B.Paste")
			(net "XM_DATA_0")
		)
		(pad "36" smd rect
			(at -3.24993 -9.6139)
			(size 0.3048 1.524)
			(layers "B.Cu" "B.Mask" "B.Paste")
			(net "XM_DATA_8")
		)
		(pad "37" smd rect
			(at -2.74955 -9.6139)
			(size 0.3048 1.524)
			(layers "B.Cu" "B.Mask" "B.Paste")
			(net "XM_DATA_1")
		)
		(pad "38" smd rect
			(at -2.25044 -9.6139)
			(size 0.3048 1.524)
			(layers "B.Cu" "B.Mask" "B.Paste")
			(net "XM_DATA_9")
		)
		(pad "39" smd rect
			(at -1.75006 -9.6139)
			(size 0.3048 1.524)
			(layers "B.Cu" "B.Mask" "B.Paste")
			(net "XM_DATA_2")
		)
		(pad "40" smd rect
			(at -1.24968 -9.6139)
			(size 0.3048 1.524)
			(layers "B.Cu" "B.Mask" "B.Paste")
			(net "XM_DATA_10")
		)
		(pad "41" smd rect
			(at -0.75057 -9.6139)
			(size 0.3048 1.524)
			(layers "B.Cu" "B.Mask" "B.Paste")
			(net "XM_DATA_3")
		)
		(pad "42" smd rect
			(at -0.25019 -9.6139)
			(size 0.3048 1.524)
			(layers "B.Cu" "B.Mask" "B.Paste")
			(net "XM_DATA_11")
		)
		(pad "43" smd rect
			(at 0.25019 -9.6139)
			(size 0.3048 1.524)
			(layers "B.Cu" "B.Mask" "B.Paste")
			(net "P3V3_STBY")
		)
		(pad "44" smd rect
			(at 0.75057 -9.6139)
			(size 0.3048 1.524)
			(layers "B.Cu" "B.Mask" "B.Paste")
			(net "XM_DATA_4")
		)
		(pad "45" smd rect
			(at 1.24968 -9.6139)
			(size 0.3048 1.524)
			(layers "B.Cu" "B.Mask" "B.Paste")
			(net "XM_DATA_12")
		)
		(pad "46" smd rect
			(at 1.75006 -9.6139)
			(size 0.3048 1.524)
			(layers "B.Cu" "B.Mask" "B.Paste")
			(net "XM_DATA_5")
		)
		(pad "47" smd rect
			(at 2.25044 -9.6139)
			(size 0.3048 1.524)
			(layers "B.Cu" "B.Mask" "B.Paste")
			(net "XM_DATA_13")
		)
		(pad "48" smd rect
			(at 2.74955 -9.6139)
			(size 0.3048 1.524)
			(layers "B.Cu" "B.Mask" "B.Paste")
			(net "XM_DATA_6")
		)
		(pad "49" smd rect
			(at 3.24993 -9.6139)
			(size 0.3048 1.524)
			(layers "B.Cu" "B.Mask" "B.Paste")
			(net "XM_DATA_14")
		)
		(pad "50" smd rect
			(at 3.75031 -9.6139)
			(size 0.3048 1.524)
			(layers "B.Cu" "B.Mask" "B.Paste")
			(net "XM_DATA_7")
		)
		(pad "51" smd rect
			(at 4.24942 -9.6139)
			(size 0.3048 1.524)
			(layers "B.Cu" "B.Mask" "B.Paste")
			(net "XM_DATA_15")
		)
		(pad "52" smd rect
			(at 4.7498 -9.6139)
			(size 0.3048 1.524)
			(layers "B.Cu" "B.Mask" "B.Paste")
			(net "GND")
		)
		(pad "53" smd rect
			(at 5.25018 -9.6139)
			(size 0.3048 1.524)
			(layers "B.Cu" "B.Mask" "B.Paste")
			(net "BYTE_N")
		)
		(pad "54" smd rect
			(at 5.75056 -9.6139)
			(size 0.3048 1.524)
			(layers "B.Cu" "B.Mask" "B.Paste")
			(net "XM_ADDR_17")
		)
		(pad "55" smd rect
			(at 6.24967 -9.6139)
			(size 0.3048 1.524)
			(layers "B.Cu" "B.Mask" "B.Paste")
			(net "Net_317")
		)
		(pad "56" smd rect
			(at 6.75005 -9.6139)
			(size 0.3048 1.524)
			(layers "B.Cu" "B.Mask" "B.Paste")
			(net "Net_318")
		)
	)
)
